(kicad_pcb
	(version 20260206)
	(generator "pcbnew")
	(generator_version "10.0")
	(general
		(thickness 1.6)
		(legacy_teardrops no)
	)
	(paper "A4")
	(title_block
		(title "Bryce Canyon_IOM_IOC_16318-2_OCP.brd")
		(comment 1 "Bryce Canyon / footprints 1602-1605 of 1605")
	)
	(layers
		(0 "F.Cu" signal "TOP")
		(4 "In1.Cu" signal "L2GND")
		(6 "In2.Cu" signal "L3")
		(8 "In3.Cu" signal "L4VCC")
		(10 "In4.Cu" signal "L5VCC")
		(12 "In5.Cu" signal "L6")
		(14 "In6.Cu" signal "L7GND")
		(2 "B.Cu" signal "BOTTOM")
		(9 "F.Adhes" user "F.Adhesive")
		(11 "B.Adhes" user "B.Adhesive")
		(13 "F.Paste" user "Package Geometry/Pastemask Top")
		(15 "B.Paste" user "Package Geometry/Pastemask Bottom")
		(5 "F.SilkS" user "Ref Des/Silkscreen Top")
		(7 "B.SilkS" user "Ref Des/Silkscreen Bottom")
		(1 "F.Mask" user "Board Geometry/Soldermask Top")
		(3 "B.Mask" user "Board Geometry/Soldermask Bottom")
		(17 "Dwgs.User" user "User.Drawings")
		(19 "Cmts.User" user "User.Comments")
		(21 "Eco1.User" user "User.Eco1")
		(23 "Eco2.User" user "User.Eco2")
		(25 "Edge.Cuts" user "Board Geometry/Outline")
		(27 "Margin" user)
		(31 "F.CrtYd" user "Package Geometry/Place Bound Top")
		(29 "B.CrtYd" user "Package Geometry/Place Bound Bottom")
		(35 "F.Fab" user "Ref Des/Assembly Top")
		(33 "B.Fab" user "Ref Des/Assembly Bottom")
	)
	(footprint ""
		(layer "B.Cu")
		(at 52.5272 -135.70712)
		(property "Reference" "R607"
			(at 0 0 0)
			(layer "B.SilkS")
			(hide yes)
			(effects
				(font
					(size 1.27 1.27)
				)
				(justify mirror)
			)
		)
		(property "Value" "0R2J-2-GP"
			(at -0.064008 -3.993896 0)
			(unlocked yes)
			(layer "B.Fab")
			(hide yes)
			(effects
				(font
					(size 1.016 1.016)
					(thickness 0.1524)
				)
				(justify mirror)
			)
		)
		(property "Device Type" "R402H16"
			(at -0.064008 -5.517896 0)
			(unlocked yes)
			(layer "B.Fab")
			(hide yes)
			(effects
				(font
					(size 1.016 1.016)
					(thickness 0.1524)
				)
				(justify mirror)
			)
		)
		(duplicate_pad_numbers_are_jumpers no)
		(fp_line
			(start -0.508 -0.9398)
			(end 0.508 -0.9398)
			(stroke
				(width 0.1524)
				(type default)
			)
			(layer "B.SilkS")
		)
		(fp_line
			(start 0.508 -0.9398)
			(end 0.508 0.9398)
			(stroke
				(width 0.1524)
				(type default)
			)
			(layer "B.SilkS")
		)
		(fp_rect
			(start 0.508 0.9398)
			(end -0.508 -0.9398)
			(stroke
				(width 0)
				(type default)
			)
			(fill no)
			(layer "B.CrtYd")
		)
		(fp_rect
			(start 0.508 0.9398)
			(end -0.508 -0.9398)
			(stroke
				(width 0)
				(type default)
			)
			(fill no)
			(layer "B.Fab")
		)
		(pad "1" smd custom
			(at 0 -0.4445 180)
			(size 0.1397 0.1397)
			(layers "B.Cu" "B.Mask" "B.Paste")
			(net "SYS_RESET_N_OUT_R")
			(options
				(clearance outline)
				(anchor circle)
			)
			(primitives
				(gr_poly
					(pts
						(arc
							(start -0.1778 0.2794)
							(mid -0.249642 0.249642)
							(end -0.2794 0.1778)
						)
						(arc
							(start -0.2794 -0.1778)
							(mid -0.249642 -0.249642)
							(end -0.1778 -0.2794)
						)
						(arc
							(start 0.1778 -0.2794)
							(mid 0.249642 -0.249642)
							(end 0.2794 -0.1778)
						)
						(arc
							(start 0.2794 0.1778)
							(mid 0.249642 0.249642)
							(end 0.1778 0.2794)
						)
					)
					(width 0)
					(fill yes)
				)
			)
		)
		(pad "2" smd custom
			(at 0 0.4445 180)
			(size 0.1397 0.1397)
			(layers "B.Cu" "B.Mask" "B.Paste")
			(net "SYS_RESET_N_OUT")
			(options
				(clearance outline)
				(anchor circle)
			)
			(primitives
				(gr_poly
					(pts
						(arc
							(start -0.1778 0.2794)
							(mid -0.249642 0.249642)
							(end -0.2794 0.1778)
						)
						(arc
							(start -0.2794 -0.1778)
							(mid -0.249642 -0.249642)
							(end -0.1778 -0.2794)
						)
						(arc
							(start 0.1778 -0.2794)
							(mid 0.249642 -0.249642)
							(end 0.2794 -0.1778)
						)
						(arc
							(start 0.2794 0.1778)
							(mid 0.249642 0.249642)
							(end 0.1778 0.2794)
						)
					)
					(width 0)
					(fill yes)
				)
			)
		)
	)
	(footprint ""
		(layer "B.Cu")
		(at 191.68999 -19.177 -90)
		(property "Reference" "C488"
			(at 0 0 90)
			(layer "B.SilkS")
			(hide yes)
			(effects
				(font
					(size 1.27 1.27)
				)
				(justify mirror)
			)
		)
		(property "Value" "SCD01U16V1KX-GP"
			(at 2.8321 -1.7399 270)
			(unlocked yes)
			(layer "B.Fab")
			(hide yes)
			(effects
				(font
					(size 1.016 1.016)
					(thickness 0.1524)
				)
				(justify mirror)
			)
		)
		(property "Device Type" "C0201H13"
			(at 2.8321 -3.2639 270)
			(unlocked yes)
			(layer "B.Fab")
			(hide yes)
			(effects
				(font
					(size 1.016 1.016)
					(thickness 0.1524)
				)
				(justify mirror)
			)
		)
		(duplicate_pad_numbers_are_jumpers no)
		(fp_rect
			(start 0.2794 0.6477)
			(end -0.2794 -0.6477)
			(stroke
				(width 0)
				(type default)
			)
			(fill no)
			(layer "B.CrtYd")
		)
		(fp_rect
			(start 0.2794 0.6477)
			(end -0.2794 -0.6477)
			(stroke
				(width 0)
				(type default)
			)
			(fill no)
			(layer "B.Fab")
		)
		(pad "1" smd custom
			(at 0 -0.2794 90)
			(size 0.0762 0.0762)
			(layers "B.Cu" "B.Mask" "B.Paste")
			(net "PHY_CON_A_TO_IOC_0_DN")
			(options
				(clearance outline)
				(anchor circle)
			)
			(primitives
				(gr_poly
					(pts
						(arc
							(start 0.1524 0.127)
							(mid 0.137521 0.162921)
							(end 0.1016 0.1778)
						)
						(arc
							(start -0.1016 0.1778)
							(mid -0.137521 0.162921)
							(end -0.1524 0.127)
						)
						(arc
							(start -0.1524 -0.127)
							(mid -0.137521 -0.162921)
							(end -0.1016 -0.1778)
						)
						(arc
							(start 0.1016 -0.1778)
							(mid 0.137521 -0.162921)
							(end 0.1524 -0.127)
						)
					)
					(width 0)
					(fill yes)
				)
			)
		)
		(pad "2" smd custom
			(at 0 0.2794 90)
			(size 0.0762 0.0762)
			(layers "B.Cu" "B.Mask" "B.Paste")
			(net "PHY_CON_A_TO_IOC_0_DN_C")
			(options
				(clearance outline)
				(anchor circle)
			)
			(primitives
				(gr_poly
					(pts
						(arc
							(start 0.1524 0.127)
							(mid 0.137521 0.162921)
							(end 0.1016 0.1778)
						)
						(arc
							(start -0.1016 0.1778)
							(mid -0.137521 0.162921)
							(end -0.1524 0.127)
						)
						(arc
							(start -0.1524 -0.127)
							(mid -0.137521 -0.162921)
							(end -0.1016 -0.1778)
						)
						(arc
							(start 0.1016 -0.1778)
							(mid 0.137521 -0.162921)
							(end 0.1524 -0.127)
						)
					)
					(width 0)
					(fill yes)
				)
			)
		)
	)
	(footprint ""
		(layer "B.Cu")
		(at 45.3644 -135.6614 180)
		(property "Reference" "R154"
			(at 0 0 0)
			(layer "B.SilkS")
			(hide yes)
			(effects
				(font
					(size 1.27 1.27)
				)
				(justify mirror)
			)
		)
		(property "Value" "0R2J-2-GP"
			(at -0.064008 -3.993896 180)
			(unlocked yes)
			(layer "B.Fab")
			(hide yes)
			(effects
				(font
					(size 1.016 1.016)
					(thickness 0.1524)
				)
				(justify mirror)
			)
		)
		(property "Device Type" "R402H16"
			(at -0.064008 -5.517896 180)
			(unlocked yes)
			(layer "B.Fab")
			(hide yes)
			(effects
				(font
					(size 1.016 1.016)
					(thickness 0.1524)
				)
				(justify mirror)
			)
		)
		(duplicate_pad_numbers_are_jumpers no)
		(fp_line
			(start 0.508 -0.9398)
			(end 0.508 0.9398)
			(stroke
				(width 0.1524)
				(type default)
			)
			(layer "B.SilkS")
		)
		(fp_line
			(start -0.508 -0.9398)
			(end 0.508 -0.9398)
			(stroke
				(width 0.1524)
				(type default)
			)
			(layer "B.SilkS")
		)
		(fp_rect
			(start 0.508 0.9398)
			(end -0.508 -0.9398)
			(stroke
				(width 0)
				(type default)
			)
			(fill no)
			(layer "B.CrtYd")
		)
		(fp_rect
			(start 0.508 0.9398)
			(end -0.508 -0.9398)
			(stroke
				(width 0)
				(type default)
			)
			(fill no)
			(layer "B.Fab")
		)
		(pad "1" smd custom
			(at 0 -0.4445)
			(size 0.1397 0.1397)
			(layers "B.Cu" "B.Mask" "B.Paste")
			(net "I2C_IOM_SDA")
			(options
				(clearance outline)
				(anchor circle)
			)
			(primitives
				(gr_poly
					(pts
						(arc
							(start -0.1778 0.2794)
							(mid -0.249642 0.249642)
							(end -0.2794 0.1778)
						)
						(arc
							(start -0.2794 -0.1778)
							(mid -0.249642 -0.249642)
							(end -0.1778 -0.2794)
						)
						(arc
							(start 0.1778 -0.2794)
							(mid 0.249642 -0.249642)
							(end 0.2794 -0.1778)
						)
						(arc
							(start 0.2794 0.1778)
							(mid 0.249642 0.249642)
							(end 0.1778 0.2794)
						)
					)
					(width 0)
					(fill yes)
				)
			)
		)
		(pad "2" smd custom
			(at 0 0.4445)
			(size 0.1397 0.1397)
			(layers "B.Cu" "B.Mask" "B.Paste")
			(net "BMC_SMB1_DAT")
			(options
				(clearance outline)
				(anchor circle)
			)
			(primitives
				(gr_poly
					(pts
						(arc
							(start -0.1778 0.2794)
							(mid -0.249642 0.249642)
							(end -0.2794 0.1778)
						)
						(arc
							(start -0.2794 -0.1778)
							(mid -0.249642 -0.249642)
							(end -0.1778 -0.2794)
						)
						(arc
							(start 0.1778 -0.2794)
							(mid 0.249642 -0.249642)
							(end 0.2794 -0.1778)
						)
						(arc
							(start 0.2794 0.1778)
							(mid 0.249642 0.249642)
							(end 0.1778 0.2794)
						)
					)
					(width 0)
					(fill yes)
				)
			)
		)
	)
	(footprint ""
		(layer "B.Cu")
		(at 192.4177 -63.7794 90)
		(property "Reference" "C419"
			(at 0 0 90)
			(layer "B.SilkS")
			(hide yes)
			(effects
				(font
					(size 1.27 1.27)
				)
				(justify mirror)
			)
		)
		(property "Value" "SCD1U6D3V1KX-GP"
			(at 2.8321 -1.7399 90)
			(unlocked yes)
			(layer "B.Fab")
			(hide yes)
			(effects
				(font
					(size 1.016 1.016)
					(thickness 0.1524)
				)
				(justify mirror)
			)
		)
		(property "Device Type" "C0201H13"
			(at 2.8321 -3.2639 90)
			(unlocked yes)
			(layer "B.Fab")
			(hide yes)
			(effects
				(font
					(size 1.016 1.016)
					(thickness 0.1524)
				)
				(justify mirror)
			)
		)
		(duplicate_pad_numbers_are_jumpers no)
		(fp_rect
			(start 0.2794 0.6477)
			(end -0.2794 -0.6477)
			(stroke
				(width 0)
				(type default)
			)
			(fill no)
			(layer "B.CrtYd")
		)
		(fp_rect
			(start 0.2794 0.6477)
			(end -0.2794 -0.6477)
			(stroke
				(width 0)
				(type default)
			)
			(fill no)
			(layer "B.Fab")
		)
		(pad "1" smd custom
			(at 0 -0.2794 270)
			(size 0.0762 0.0762)
			(layers "B.Cu" "B.Mask" "B.Paste")
			(net "P0V975")
			(options
				(clearance outline)
				(anchor circle)
			)
			(primitives
				(gr_poly
					(pts
						(arc
							(start 0.1524 0.127)
							(mid 0.137521 0.162921)
							(end 0.1016 0.1778)
						)
						(arc
							(start -0.1016 0.1778)
							(mid -0.137521 0.162921)
							(end -0.1524 0.127)
						)
						(arc
							(start -0.1524 -0.127)
							(mid -0.137521 -0.162921)
							(end -0.1016 -0.1778)
						)
						(arc
							(start 0.1016 -0.1778)
							(mid 0.137521 -0.162921)
							(end 0.1524 -0.127)
						)
					)
					(width 0)
					(fill yes)
				)
			)
		)
		(pad "2" smd custom
			(at 0 0.2794 270)
			(size 0.0762 0.0762)
			(layers "B.Cu" "B.Mask" "B.Paste")
			(net "GND")
			(options
				(clearance outline)
				(anchor circle)
			)
			(primitives
				(gr_poly
					(pts
						(arc
							(start 0.1524 0.127)
							(mid 0.137521 0.162921)
							(end 0.1016 0.1778)
						)
						(arc
							(start -0.1016 0.1778)
							(mid -0.137521 0.162921)
							(end -0.1524 0.127)
						)
						(arc
							(start -0.1524 -0.127)
							(mid -0.137521 -0.162921)
							(end -0.1016 -0.1778)
						)
						(arc
							(start 0.1016 -0.1778)
							(mid 0.137521 -0.162921)
							(end 0.1524 -0.127)
						)
					)
					(width 0)
					(fill yes)
				)
			)
		)
	)
)
